# T6G (Grand Teton) — schematic netlist excerpt (pin names and nets, part order shuffled) for the footprints in the layout excerpt that follows; sources: Cadence DE-HDL packaged netlist, KiCad conversion of 04192023_DAF0TMB3IC0_F0TG_MB_C_brd_V02_OCP.brd

PU44  ISL99390FRZTR5935  ISL99390FRZ-TR5935 IC  pkg QFN21_6X5XB  page 225
  VOS  = PVDD11_S3_P1_VOS1
  AGND  = GND
  VCC  = PVDD11_S3_P1_VCC1
  PVCC  = PVDD11_S3_P1_PVCC
  PGND1  = GND
  GL1  = NC_PVDD11_S3_P1_GL1_1
  PGND2  = GND
  SW  = SW_PVDD11_S3_P1_SW1
  VIN1  = SW_P12V_AUX_PVDD11_S3_P1_FLT
  VIN2  = SW_P12V_AUX_PVDD11_S3_P1_FLT
  DNC  = NC_PVDD11_S3_P1_DNC1
  PHASE  = SW_PVDD11_S3_P1_PH1
  BOOT  = SW_PVDD11_S3_P1_BOOT1
  PWM  = PVDD11_S3_P1_PWM1
  EN  = PVDD11_S3_P1_VCC1
  TOUT_FLT  = PVDD11_S3_P1_TEMP0
  LSET  = PVDD11_S3_P1_LSET1
  IOUT  = PVDD11_S3_P1_IMON1
  REFIN  = PVDD11_S3_P1_VCCS
  PGND3  = GND
  GL2  = NC_PVDD11_S3_P1_GL2_1

(kicad_pcb
	(version 20260206)
	(generator "pcbnew")
	(generator_version "10.0")
	(general
		(thickness 1.6)
		(legacy_teardrops no)
	)
	(paper "A4")
	(title_block
		(title "04192023_DAF0TMB3IC0_F0TG_MB_C_brd_V02_OCP.brd")
		(comment 1 "Grand Teton / footprints 3118-3118 of 8354")
	)
	(layers
		(0 "F.Cu" signal "TOP")
		(4 "In1.Cu" signal "GND")
		(6 "In2.Cu" signal "IN1")
		(8 "In3.Cu" signal "GND1")
		(10 "In4.Cu" signal "IN2")
		(12 "In5.Cu" signal "GND2")
		(14 "In6.Cu" signal "IN3")
		(16 "In7.Cu" signal "GND3")
		(18 "In8.Cu" signal "VCC")
		(20 "In9.Cu" signal "VCC1")
		(22 "In10.Cu" signal "GND4")
		(24 "In11.Cu" signal "IN4")
		(26 "In12.Cu" signal "GND5")
		(28 "In13.Cu" signal "IN5")
		(30 "In14.Cu" signal "GND6")
		(32 "In15.Cu" signal "IN6")
		(34 "In16.Cu" signal "GND7")
		(2 "B.Cu" signal "BOTTOM")
		(9 "F.Adhes" user "F.Adhesive")
		(11 "B.Adhes" user "B.Adhesive")
		(13 "F.Paste" user "Package Geometry/Pastemask Top")
		(15 "B.Paste" user "Package Geometry/Pastemask Bottom")
		(5 "F.SilkS" user "Ref Des/Silkscreen Top")
		(7 "B.SilkS" user "Ref Des/Silkscreen Bottom")
		(1 "F.Mask" user "Board Geometry/Soldermask Top")
		(3 "B.Mask" user "Board Geometry/Soldermask Bottom")
		(17 "Dwgs.User" user "User.Drawings")
		(19 "Cmts.User" user "User.Comments")
		(21 "Eco1.User" user "User.Eco1")
		(23 "Eco2.User" user "User.Eco2")
		(25 "Edge.Cuts" user "Board Geometry/Outline")
		(27 "Margin" user)
		(31 "F.CrtYd" user "Package Geometry/Place Bound Top")
		(29 "B.CrtYd" user "Package Geometry/Place Bound Bottom")
		(35 "F.Fab" user "Ref Des/Assembly Top")
		(33 "B.Fab" user "Ref Des/Assembly Bottom")
	)
	(footprint ""
		(layer "F.Cu")
		(at 182.919878 -351.295462)
		(property "Reference" "PU44"
			(at -5.9436 -7.47141 0)
			(unlocked yes)
			(layer "F.SilkS")
			(effects
				(font
					(size 0.7874 0.5842)
					(thickness 0.1524)
				)
				(justify left)
			)
		)
		(property "Value" ""
			(at 0 0 0)
			(layer "F.Fab")
			(effects
				(font
					(size 1.27 1.27)
				)
			)
		)
		(duplicate_pad_numbers_are_jumpers no)
		(fp_line
			(start -2.500122 -2.999994)
			(end -2.24409 -2.999994)
			(stroke
				(width 0.1524)
				(type default)
			)
			(layer "F.SilkS")
		)
		(fp_line
			(start -2.500122 -2.529078)
			(end -2.500122 -2.999994)
			(stroke
				(width 0.1524)
				(type default)
			)
			(layer "F.SilkS")
		)
		(fp_line
			(start -2.500122 0.6604)
			(end -2.500122 0.229108)
			(stroke
				(width 0.1524)
				(type default)
			)
			(layer "F.SilkS")
		)
		(fp_line
			(start -2.500122 2.999994)
			(end -2.500122 2.339594)
			(stroke
				(width 0.1524)
				(type default)
			)
			(layer "F.SilkS")
		)
		(fp_line
			(start -2.2987 2.999994)
			(end -2.500122 2.999994)
			(stroke
				(width 0.1524)
				(type default)
			)
			(layer "F.SilkS")
		)
		(fp_line
			(start 2.31394 -2.999994)
			(end 2.500122 -2.999994)
			(stroke
				(width 0.1524)
				(type default)
			)
			(layer "F.SilkS")
		)
		(fp_line
			(start 2.500122 -2.999994)
			(end 2.500122 -2.44348)
			(stroke
				(width 0.1524)
				(type default)
			)
			(layer "F.SilkS")
		)
		(fp_line
			(start 2.500122 2.339594)
			(end 2.500122 2.999994)
			(stroke
				(width 0.1524)
				(type default)
			)
			(layer "F.SilkS")
		)
		(fp_line
			(start 2.500122 2.999994)
			(end 2.2987 2.999994)
			(stroke
				(width 0.1524)
				(type default)
			)
			(layer "F.SilkS")
		)
		(fp_poly
			(pts
				(xy -2.732278 -2.41681) (xy -3.405886 -2.641346) (xy -2.956814 -3.090418)
			)
			(stroke
				(width 0)
				(type default)
			)
			(fill yes)
			(layer "F.SilkS")
		)
		(fp_line
			(start -2.500122 -2.999994)
			(end 2.500122 -2.999994)
			(stroke
				(width 0.1)
				(type default)
			)
			(layer "F.Fab")
		)
		(fp_line
			(start -2.500122 2.999994)
			(end -2.500122 -2.999994)
			(stroke
				(width 0.1)
				(type default)
			)
			(layer "F.Fab")
		)
		(fp_line
			(start 2.500122 -2.999994)
			(end 2.500122 2.999994)
			(stroke
				(width 0.1)
				(type default)
			)
			(layer "F.Fab")
		)
		(fp_line
			(start 2.500122 2.999994)
			(end -2.500122 2.999994)
			(stroke
				(width 0.1)
				(type default)
			)
			(layer "F.Fab")
		)
		(fp_poly
			(pts
				(xy -4.218432 -2.783078) (xy -4.218432 -1.767078) (xy -3.202432 -2.275078)
			)
			(stroke
				(width 0)
				(type default)
			)
			(fill yes)
			(layer "F.Fab")
		)
		(pad "1" smd rect
			(at -2.400046 -2.275078 90)
			(size 0.2286 0.6096)
			(layers "F.Cu" "F.Mask" "F.Paste")
			(net "PVDD11_S3_P1_VOS1")
		)
		(pad "2" smd rect
			(at -2.400046 -1.82499 90)
			(size 0.2286 0.6096)
			(layers "F.Cu" "F.Mask" "F.Paste")
			(net "GND")
		)
		(pad "3" smd rect
			(at -2.400046 -1.374902 90)
			(size 0.2286 0.6096)
			(layers "F.Cu" "F.Mask" "F.Paste")
			(net "PVDD11_S3_P1_VCC1")
		)
		(pad "4" smd rect
			(at -2.400046 -0.925068 90)
			(size 0.2286 0.6096)
			(layers "F.Cu" "F.Mask" "F.Paste")
			(net "PVDD11_S3_P1_PVCC")
		)
		(pad "5" smd rect
			(at -2.400046 -0.47498 90)
			(size 0.2286 0.6096)
			(layers "F.Cu" "F.Mask" "F.Paste")
			(net "GND")
		)
		(pad "6" smd rect
			(at -2.400046 -0.024892 90)
			(size 0.2286 0.6096)
			(layers "F.Cu" "F.Mask" "F.Paste")
			(net "NC_PVDD11_S3_P1_GL1_1")
		)
		(pad "7_9-20_24" smd circle
			(at 0 1.150112 90)
			(size 0 0)
			(layers "F.Cu" "F.Mask" "F.Paste")
			(net "GND")
		)
		(pad "10_19" smd rect
			(at 0 2.899918 90)
			(size 0.6096 4.318)
			(layers "F.Cu" "F.Mask" "F.Paste")
			(net "SW_PVDD11_S3_P1_SW1")
		)
		(pad "25_29" smd rect
			(at 1.549908 -1.279906 270)
			(size 2.0574 2.3114)
			(layers "F.Cu" "F.Mask" "F.Paste")
			(net "SW_P12V_AUX_PVDD11_S3_P1_FLT")
		)
		(pad "30" smd rect
			(at 2.05994 -2.899918)
			(size 0.2286 0.6096)
			(layers "F.Cu" "F.Mask" "F.Paste")
			(net "SW_P12V_AUX_PVDD11_S3_P1_FLT")
		)
		(pad "31" smd rect
			(at 1.610106 -2.899918)
			(size 0.2286 0.6096)
			(layers "F.Cu" "F.Mask" "F.Paste")
			(net "NC_PVDD11_S3_P1_DNC1")
		)
		(pad "32" smd rect
			(at 1.160018 -2.899918)
			(size 0.2286 0.6096)
			(layers "F.Cu" "F.Mask" "F.Paste")
			(net "SW_PVDD11_S3_P1_PH1")
		)
		(pad "33" smd rect
			(at 0.70993 -2.899918)
			(size 0.2286 0.6096)
			(layers "F.Cu" "F.Mask" "F.Paste")
			(net "SW_PVDD11_S3_P1_BOOT1")
		)
		(pad "34" smd rect
			(at 0.260096 -2.899918)
			(size 0.2286 0.6096)
			(layers "F.Cu" "F.Mask" "F.Paste")
			(net "PVDD11_S3_P1_PWM1")
		)
		(pad "35" smd rect
			(at -0.189992 -2.899918)
			(size 0.2286 0.6096)
			(layers "F.Cu" "F.Mask" "F.Paste")
			(net "PVDD11_S3_P1_VCC1")
		)
		(pad "36" smd rect
			(at -0.64008 -2.899918)
			(size 0.2286 0.6096)
			(layers "F.Cu" "F.Mask" "F.Paste")
			(net "PVDD11_S3_P1_TEMP0")
		)
		(pad "37" smd rect
			(at -1.089914 -2.899918)
			(size 0.2286 0.6096)
			(layers "F.Cu" "F.Mask" "F.Paste")
			(net "PVDD11_S3_P1_LSET1")
		)
		(pad "38" smd rect
			(at -1.540002 -2.899918)
			(size 0.2286 0.6096)
			(layers "F.Cu" "F.Mask" "F.Paste")
			(net "PVDD11_S3_P1_IMON1")
		)
		(pad "39" smd rect
			(at -1.99009 -2.899918)
			(size 0.2286 0.6096)
			(layers "F.Cu" "F.Mask" "F.Paste")
			(net "PVDD11_S3_P1_VCCS")
		)
		(pad "40" smd rect
			(at -0.87503 -1.27508)
			(size 1.7526 1.9558)
			(layers "F.Cu" "F.Mask" "F.Paste")
			(net "GND")
		)
		(pad "41" smd rect
			(at -1.525016 0.249936 270)
			(size 0.3048 0.4572)
			(layers "F.Cu" "F.Mask" "F.Paste")
			(net "NC_PVDD11_S3_P1_GL2_1")
		)
		(zone
			(layer "F.Cu")
			(hatch none 0.5)
			(connect_pads
				(clearance 0)
			)
			(min_thickness 0.25)
			(keepout
				(tracks not_allowed)
				(vias allowed)
				(pads allowed)
				(copperpour not_allowed)
				(footprints allowed)
			)
			(placement
				(enabled no)
				(sheetname "")
			)
			(fill
				(thermal_gap 0.5)
				(thermal_bridge_width 0.5)
				(island_removal_mode 0)
			)
			(polygon
				(pts
					(xy 180.419756 -348.751398) (xy 180.419756 -349.044768) (xy 185.42 -349.044768) (xy 185.42 -348.295468)
					(xy 185.129678 -348.295468) (xy 185.129678 -348.751144) (xy 180.710078 -348.751144) (xy 180.710078 -348.751398)
				)
			)
		)
		(zone
			(layer "F.Cu")
			(hatch none 0.5)
			(connect_pads
				(clearance 0)
			)
			(min_thickness 0.25)
			(keepout
				(tracks not_allowed)
				(vias allowed)
				(pads allowed)
				(copperpour not_allowed)
				(footprints allowed)
			)
			(placement
				(enabled no)
				(sheetname "")
			)
			(fill
				(thermal_gap 0.5)
				(thermal_bridge_width 0.5)
				(island_removal_mode 0)
			)
			(polygon
				(pts
					(xy 182.971948 -351.541842) (xy 182.971948 -353.599242) (xy 181.117748 -353.599242) (xy 181.117748 -353.358196)
					(xy 180.875432 -353.358196) (xy 180.875432 -353.83978) (xy 184.684924 -353.83978) (xy 184.684924 -353.654868)
					(xy 183.263286 -353.654868) (xy 183.263286 -351.495868) (xy 185.42 -351.495868) (xy 185.42 -351.246186)
					(xy 183.267604 -351.246186)
				)
			)
		)
	)
)
